FILE NAME: R4006-B0001-02_R01_ASM.ZIP

      ITEM DESCRIPTION                                   FILE NAME
      GERBER FORMAT INFORMATION                          art_param.txt
      GERBER FORMAT INFORMATION                          art_aper.txt
                                                         RS274X  5.5A

      N/C DRILL PARAMETER FILE                           nc_param.txt


      SOLDERPASTE PRIMARY TOP                            R4006-B0001-02_R01_TPM.art
      SOLDERPASTE SECONDARY BOTTOM                       R4006-B0001-02_R01_BPM.art
      ASSEMBLY DRAWING GERBER FORMAT  (PRIMARY SIDE)     R4006-B0001-02_R01_TAS.art
      ASSEMBLY DRAWING GERBER FORMAT  (SECONDARY SIDE)   R4006-B0001-02_R01_BAS.art
      ASSEMBLY GERBER FORMAT                             R4006-B0001-02_R01_ASM.art

      ASSEMBLY DRAWING PDF FORMAT                        R4006-B0001-01_R01_ASM.pdf
      FABMASTER CAM DATABASE FORMAT                      R4006-B0001-02_R01_FABMASTER.cad
      VALOR ODB++ CAM DATABASE                           R4006-B0001-02_R01_ODB.tgz
      PLACEMENT FILE                                     R4006-B0001-02_R01_PLACEMENT.txt
